(kicad_pcb
	(version 20260206)
	(generator "pcbnew")
	(generator_version "10.0")
	(general
		(thickness 1.6)
		(legacy_teardrops no)
	)
	(paper "A4")
	(title_block
		(title "01162023_DA0F0TEBIF0_F0T_Expander_BD_F_brd_V02_OCP.brd")
		(comment 1 "Grand Teton / footprints 2395-2400 of 9728")
	)
	(layers
		(0 "F.Cu" signal "TOP")
		(4 "In1.Cu" signal "GND")
		(6 "In2.Cu" signal "VCC")
		(8 "In3.Cu" signal "VCC1")
		(10 "In4.Cu" signal "GND1")
		(12 "In5.Cu" signal "IN1")
		(14 "In6.Cu" signal "GND2")
		(16 "In7.Cu" signal "IN2")
		(18 "In8.Cu" signal "GND3")
		(20 "In9.Cu" signal "IN3")
		(22 "In10.Cu" signal "GND4")
		(24 "In11.Cu" signal "IN4")
		(26 "In12.Cu" signal "GND5")
		(28 "In13.Cu" signal "IN5")
		(30 "In14.Cu" signal "GND6")
		(32 "In15.Cu" signal "IN6")
		(34 "In16.Cu" signal "GND7")
		(2 "B.Cu" signal "BOTTOM")
		(9 "F.Adhes" user "F.Adhesive")
		(11 "B.Adhes" user "B.Adhesive")
		(13 "F.Paste" user "Package Geometry/Pastemask Top")
		(15 "B.Paste" user "Package Geometry/Pastemask Bottom")
		(5 "F.SilkS" user "Ref Des/Silkscreen Top")
		(7 "B.SilkS" user "Ref Des/Silkscreen Bottom")
		(1 "F.Mask" user "Board Geometry/Soldermask Top")
		(3 "B.Mask" user "Board Geometry/Soldermask Bottom")
		(17 "Dwgs.User" user "User.Drawings")
		(19 "Cmts.User" user "User.Comments")
		(21 "Eco1.User" user "User.Eco1")
		(23 "Eco2.User" user "User.Eco2")
		(25 "Edge.Cuts" user "Board Geometry/Outline")
		(27 "Margin" user)
		(31 "F.CrtYd" user "Package Geometry/Place Bound Top")
		(29 "B.CrtYd" user "Package Geometry/Place Bound Bottom")
		(35 "F.Fab" user "Ref Des/Assembly Top")
		(33 "B.Fab" user "Ref Des/Assembly Bottom")
	)
	(footprint ""
		(layer "F.Cu")
		(at 372.901718 -240.6904 180)
		(property "Reference" "R6403"
			(at 0 0 180)
			(layer "F.SilkS")
			(hide yes)
			(effects
				(font
					(size 1.27 1.27)
				)
			)
		)
		(property "Value" ""
			(at 0 0 180)
			(layer "F.Fab")
			(effects
				(font
					(size 1.27 1.27)
				)
			)
		)
		(duplicate_pad_numbers_are_jumpers no)
		(fp_line
			(start 0.7874 0.4064)
			(end -0.7874 0.4064)
			(stroke
				(width 0.1524)
				(type default)
			)
			(layer "F.SilkS")
		)
		(fp_line
			(start 0.7874 -0.4064)
			(end 0.7874 0.4064)
			(stroke
				(width 0.1524)
				(type default)
			)
			(layer "F.SilkS")
		)
		(fp_line
			(start -0.7874 0.4064)
			(end -0.7874 -0.4064)
			(stroke
				(width 0.1524)
				(type default)
			)
			(layer "F.SilkS")
		)
		(fp_line
			(start -0.7874 -0.4064)
			(end 0.7874 -0.4064)
			(stroke
				(width 0.1524)
				(type default)
			)
			(layer "F.SilkS")
		)
		(fp_line
			(start 0.67945 0.3048)
			(end 0.120396 0.3048)
			(stroke
				(width 0.1)
				(type default)
			)
			(layer "F.Fab")
		)
		(fp_line
			(start 0.67945 -0.3048)
			(end 0.67945 0.3048)
			(stroke
				(width 0.1)
				(type default)
			)
			(layer "F.Fab")
		)
		(fp_line
			(start 0.12065 -0.2794)
			(end 0.12065 -0.3048)
			(stroke
				(width 0.1)
				(type default)
			)
			(layer "F.Fab")
		)
		(fp_line
			(start 0.12065 -0.3048)
			(end 0.67945 -0.3048)
			(stroke
				(width 0.1)
				(type default)
			)
			(layer "F.Fab")
		)
		(fp_line
			(start 0.120396 0.3048)
			(end 0.120396 0.2794)
			(stroke
				(width 0.1)
				(type default)
			)
			(layer "F.Fab")
		)
		(fp_line
			(start 0.120396 0.2794)
			(end -0.12065 0.2794)
			(stroke
				(width 0.1)
				(type default)
			)
			(layer "F.Fab")
		)
		(fp_line
			(start -0.12065 0.3048)
			(end -0.67945 0.3048)
			(stroke
				(width 0.1)
				(type default)
			)
			(layer "F.Fab")
		)
		(fp_line
			(start -0.12065 0.2794)
			(end -0.12065 0.3048)
			(stroke
				(width 0.1)
				(type default)
			)
			(layer "F.Fab")
		)
		(fp_line
			(start -0.12065 -0.2794)
			(end 0.12065 -0.2794)
			(stroke
				(width 0.1)
				(type default)
			)
			(layer "F.Fab")
		)
		(fp_line
			(start -0.12065 -0.305054)
			(end -0.12065 -0.2794)
			(stroke
				(width 0.1)
				(type default)
			)
			(layer "F.Fab")
		)
		(fp_line
			(start -0.67945 0.3048)
			(end -0.67945 -0.305054)
			(stroke
				(width 0.1)
				(type default)
			)
			(layer "F.Fab")
		)
		(fp_line
			(start -0.67945 -0.305054)
			(end -0.12065 -0.305054)
			(stroke
				(width 0.1)
				(type default)
			)
			(layer "F.Fab")
		)
		(pad "1" smd circle
			(at -0.40005 0 180)
			(size 0 0)
			(layers "F.Cu" "F.Mask" "F.Paste")
			(net "GND")
		)
		(pad "2" smd circle
			(at 0.40005 0 180)
			(size 0 0)
			(layers "F.Cu" "F.Mask" "F.Paste")
			(net "PWRGD_P12V_AUX_BUF")
		)
	)
	(footprint ""
		(layer "F.Cu")
		(at 410.12999 -171.661328 180)
		(property "Reference" "C943"
			(at 0 0 180)
			(layer "F.SilkS")
			(hide yes)
			(effects
				(font
					(size 1.27 1.27)
				)
			)
		)
		(property "Value" ""
			(at 0 0 180)
			(layer "F.Fab")
			(effects
				(font
					(size 1.27 1.27)
				)
			)
		)
		(duplicate_pad_numbers_are_jumpers no)
		(fp_line
			(start 0.7874 0.4064)
			(end -0.7874 0.4064)
			(stroke
				(width 0.1524)
				(type default)
			)
			(layer "F.SilkS")
		)
		(fp_line
			(start 0.7874 -0.4064)
			(end 0.7874 0.4064)
			(stroke
				(width 0.1524)
				(type default)
			)
			(layer "F.SilkS")
		)
		(fp_line
			(start -0.7874 0.4064)
			(end -0.7874 -0.4064)
			(stroke
				(width 0.1524)
				(type default)
			)
			(layer "F.SilkS")
		)
		(fp_line
			(start -0.7874 -0.4064)
			(end 0.7874 -0.4064)
			(stroke
				(width 0.1524)
				(type default)
			)
			(layer "F.SilkS")
		)
		(fp_line
			(start 0.67945 0.3048)
			(end 0.120396 0.3048)
			(stroke
				(width 0.1)
				(type default)
			)
			(layer "F.Fab")
		)
		(fp_line
			(start 0.67945 -0.3048)
			(end 0.67945 0.3048)
			(stroke
				(width 0.1)
				(type default)
			)
			(layer "F.Fab")
		)
		(fp_line
			(start 0.12065 -0.2794)
			(end 0.12065 -0.3048)
			(stroke
				(width 0.1)
				(type default)
			)
			(layer "F.Fab")
		)
		(fp_line
			(start 0.12065 -0.3048)
			(end 0.67945 -0.3048)
			(stroke
				(width 0.1)
				(type default)
			)
			(layer "F.Fab")
		)
		(fp_line
			(start 0.120396 0.3048)
			(end 0.120396 0.2794)
			(stroke
				(width 0.1)
				(type default)
			)
			(layer "F.Fab")
		)
		(fp_line
			(start 0.120396 0.2794)
			(end -0.12065 0.2794)
			(stroke
				(width 0.1)
				(type default)
			)
			(layer "F.Fab")
		)
		(fp_line
			(start -0.12065 0.3048)
			(end -0.67945 0.3048)
			(stroke
				(width 0.1)
				(type default)
			)
			(layer "F.Fab")
		)
		(fp_line
			(start -0.12065 0.2794)
			(end -0.12065 0.3048)
			(stroke
				(width 0.1)
				(type default)
			)
			(layer "F.Fab")
		)
		(fp_line
			(start -0.12065 -0.2794)
			(end 0.12065 -0.2794)
			(stroke
				(width 0.1)
				(type default)
			)
			(layer "F.Fab")
		)
		(fp_line
			(start -0.12065 -0.305054)
			(end -0.12065 -0.2794)
			(stroke
				(width 0.1)
				(type default)
			)
			(layer "F.Fab")
		)
		(fp_line
			(start -0.67945 0.3048)
			(end -0.67945 -0.305054)
			(stroke
				(width 0.1)
				(type default)
			)
			(layer "F.Fab")
		)
		(fp_line
			(start -0.67945 -0.305054)
			(end -0.12065 -0.305054)
			(stroke
				(width 0.1)
				(type default)
			)
			(layer "F.Fab")
		)
		(pad "1" smd circle
			(at -0.40005 0 180)
			(size 0 0)
			(layers "F.Cu" "F.Mask" "F.Paste")
			(net "P3V3_NIC6")
		)
		(pad "2" smd circle
			(at 0.40005 0 180)
			(size 0 0)
			(layers "F.Cu" "F.Mask" "F.Paste")
			(net "GND")
		)
	)
	(footprint ""
		(layer "F.Cu")
		(at 118.054628 -343.952322 90)
		(property "Reference" "C344"
			(at 0 0 90)
			(layer "F.SilkS")
			(hide yes)
			(effects
				(font
					(size 1.27 1.27)
				)
			)
		)
		(property "Value" ""
			(at 0 0 90)
			(layer "F.Fab")
			(effects
				(font
					(size 1.27 1.27)
				)
			)
		)
		(duplicate_pad_numbers_are_jumpers no)
		(fp_line
			(start 0.299974 -0.150114)
			(end 0.299974 0.150114)
			(stroke
				(width 0.1)
				(type default)
			)
			(layer "F.Fab")
		)
		(fp_line
			(start -0.299974 -0.150114)
			(end 0.299974 -0.150114)
			(stroke
				(width 0.1)
				(type default)
			)
			(layer "F.Fab")
		)
		(fp_line
			(start 0.299974 0.150114)
			(end -0.299974 0.150114)
			(stroke
				(width 0.1)
				(type default)
			)
			(layer "F.Fab")
		)
		(fp_line
			(start -0.299974 0.150114)
			(end -0.299974 -0.150114)
			(stroke
				(width 0.1)
				(type default)
			)
			(layer "F.Fab")
		)
		(pad "1" smd rect
			(at -0.2667 0 90)
			(size 0.3048 0.381)
			(layers "F.Cu" "F.Mask" "F.Paste")
			(net "P5E_PEX1_STN6_TX_DP<109>")
		)
		(pad "2" smd rect
			(at 0.2667 0 90)
			(size 0.3048 0.381)
			(layers "F.Cu" "F.Mask" "F.Paste")
			(net "P5E_PEX1_STN6_TX_C_DP<109>")
		)
	)
	(footprint ""
		(layer "F.Cu")
		(at 377.082558 -29.875734)
		(property "Reference" "PU132"
			(at -3.37058 -1.99644 90)
			(unlocked yes)
			(layer "F.SilkS")
			(effects
				(font
					(size 0.7874 0.5842)
					(thickness 0.1524)
				)
			)
		)
		(property "Value" ""
			(at 0 0 0)
			(layer "F.Fab")
			(effects
				(font
					(size 1.27 1.27)
				)
			)
		)
		(duplicate_pad_numbers_are_jumpers no)
		(fp_line
			(start -1.239774 -1.495298)
			(end 1.239774 -1.495298)
			(stroke
				(width 0.1524)
				(type default)
			)
			(layer "F.SilkS")
		)
		(fp_line
			(start -1.239774 1.495298)
			(end -1.239774 -1.495298)
			(stroke
				(width 0.1524)
				(type default)
			)
			(layer "F.SilkS")
		)
		(fp_line
			(start 1.239774 -1.495298)
			(end 1.239774 1.495298)
			(stroke
				(width 0.1524)
				(type default)
			)
			(layer "F.SilkS")
		)
		(fp_line
			(start 1.239774 1.495298)
			(end -1.239774 1.495298)
			(stroke
				(width 0.1524)
				(type default)
			)
			(layer "F.SilkS")
		)
		(fp_poly
			(pts
				(xy -2.03962 -1.238504) (xy -2.757932 -0.520192) (xy -1.68021 -0.161036)
			)
			(stroke
				(width 0)
				(type default)
			)
			(fill yes)
			(layer "F.SilkS")
		)
		(fp_line
			(start -0.8001 -1.050036)
			(end 0.8001 -1.050036)
			(stroke
				(width 0.1)
				(type default)
			)
			(layer "F.Fab")
		)
		(fp_line
			(start -0.8001 1.050036)
			(end -0.8001 -1.050036)
			(stroke
				(width 0.1)
				(type default)
			)
			(layer "F.Fab")
		)
		(fp_line
			(start 0.8001 -1.050036)
			(end 0.8001 1.050036)
			(stroke
				(width 0.1)
				(type default)
			)
			(layer "F.Fab")
		)
		(fp_line
			(start 0.8001 1.050036)
			(end -0.8001 1.050036)
			(stroke
				(width 0.1)
				(type default)
			)
			(layer "F.Fab")
		)
		(fp_poly
			(pts
				(xy -2.458974 -0.508) (xy -2.458974 0.508) (xy -1.442974 0)
			)
			(stroke
				(width 0)
				(type default)
			)
			(fill yes)
			(layer "F.Fab")
		)
		(pad "1_2" smd circle
			(at -0.374904 0 90)
			(size 0 0)
			(layers "F.Cu" "F.Mask" "F.Paste")
			(net "P3V3_AUX")
		)
		(pad "3" smd rect
			(at -0.499872 0.999998)
			(size 0.254 0.7112)
			(layers "F.Cu" "F.Mask" "F.Paste")
			(net "GND")
		)
		(pad "4" smd rect
			(at 0 0.999998)
			(size 0.254 0.7112)
			(layers "F.Cu" "F.Mask" "F.Paste")
			(net "P3V3_SSD13_CO_ILIMIT")
		)
		(pad "5" smd rect
			(at 0.499872 0.999998)
			(size 0.254 0.7112)
			(layers "F.Cu" "F.Mask" "F.Paste")
			(net "P3V3_SSD13_CO_MODE")
		)
		(pad "6_7" smd circle
			(at 0.374904 0 270)
			(size 0 0)
			(layers "F.Cu" "F.Mask" "F.Paste")
			(net "P3V3_SSD13")
		)
		(pad "8" smd rect
			(at 0.499872 -0.999998)
			(size 0.254 0.7112)
			(layers "F.Cu" "F.Mask" "F.Paste")
			(net "P3V3_SSD13_CO_GATE")
		)
		(pad "9" smd rect
			(at 0 -0.999998)
			(size 0.254 0.7112)
			(layers "F.Cu" "F.Mask" "F.Paste")
			(net "P3V3_SSD13_CO_EN")
		)
		(pad "10" smd rect
			(at -0.499872 -0.999998)
			(size 0.254 0.7112)
			(layers "F.Cu" "F.Mask" "F.Paste")
			(net "P3V3_SSD13_CO_DV_DT")
		)
	)
	(footprint ""
		(layer "F.Cu")
		(at 438.152032 -289.230816 90)
		(property "Reference" "R4002"
			(at 0 0 90)
			(layer "F.SilkS")
			(hide yes)
			(effects
				(font
					(size 1.27 1.27)
				)
			)
		)
		(property "Value" ""
			(at 0 0 90)
			(layer "F.Fab")
			(effects
				(font
					(size 1.27 1.27)
				)
			)
		)
		(duplicate_pad_numbers_are_jumpers no)
		(fp_line
			(start 0.7874 -0.4064)
			(end 0.7874 0.4064)
			(stroke
				(width 0.1524)
				(type default)
			)
			(layer "F.SilkS")
		)
		(fp_line
			(start -0.7874 -0.4064)
			(end 0.7874 -0.4064)
			(stroke
				(width 0.1524)
				(type default)
			)
			(layer "F.SilkS")
		)
		(fp_line
			(start 0.7874 0.4064)
			(end -0.7874 0.4064)
			(stroke
				(width 0.1524)
				(type default)
			)
			(layer "F.SilkS")
		)
		(fp_line
			(start -0.7874 0.4064)
			(end -0.7874 -0.4064)
			(stroke
				(width 0.1524)
				(type default)
			)
			(layer "F.SilkS")
		)
		(fp_line
			(start -0.12065 -0.305054)
			(end -0.12065 -0.2794)
			(stroke
				(width 0.1)
				(type default)
			)
			(layer "F.Fab")
		)
		(fp_line
			(start -0.67945 -0.305054)
			(end -0.12065 -0.305054)
			(stroke
				(width 0.1)
				(type default)
			)
			(layer "F.Fab")
		)
		(fp_line
			(start 0.67945 -0.3048)
			(end 0.67945 0.3048)
			(stroke
				(width 0.1)
				(type default)
			)
			(layer "F.Fab")
		)
		(fp_line
			(start 0.12065 -0.3048)
			(end 0.67945 -0.3048)
			(stroke
				(width 0.1)
				(type default)
			)
			(layer "F.Fab")
		)
		(fp_line
			(start 0.12065 -0.2794)
			(end 0.12065 -0.3048)
			(stroke
				(width 0.1)
				(type default)
			)
			(layer "F.Fab")
		)
		(fp_line
			(start -0.12065 -0.2794)
			(end 0.12065 -0.2794)
			(stroke
				(width 0.1)
				(type default)
			)
			(layer "F.Fab")
		)
		(fp_line
			(start 0.120396 0.2794)
			(end -0.12065 0.2794)
			(stroke
				(width 0.1)
				(type default)
			)
			(layer "F.Fab")
		)
		(fp_line
			(start -0.12065 0.2794)
			(end -0.12065 0.3048)
			(stroke
				(width 0.1)
				(type default)
			)
			(layer "F.Fab")
		)
		(fp_line
			(start 0.67945 0.3048)
			(end 0.120396 0.3048)
			(stroke
				(width 0.1)
				(type default)
			)
			(layer "F.Fab")
		)
		(fp_line
			(start 0.120396 0.3048)
			(end 0.120396 0.2794)
			(stroke
				(width 0.1)
				(type default)
			)
			(layer "F.Fab")
		)
		(fp_line
			(start -0.12065 0.3048)
			(end -0.67945 0.3048)
			(stroke
				(width 0.1)
				(type default)
			)
			(layer "F.Fab")
		)
		(fp_line
			(start -0.67945 0.3048)
			(end -0.67945 -0.305054)
			(stroke
				(width 0.1)
				(type default)
			)
			(layer "F.Fab")
		)
		(pad "1" smd circle
			(at -0.40005 0 90)
			(size 0 0)
			(layers "F.Cu" "F.Mask" "F.Paste")
			(net "SMB_PEX3_PCA9555_SDA")
		)
		(pad "2" smd circle
			(at 0.40005 0 90)
			(size 0 0)
			(layers "F.Cu" "F.Mask" "F.Paste")
			(net "SMB_PEX3_HOST_LS_SDA")
		)
	)
	(footprint ""
		(layer "F.Cu")
		(at 63.6778 -115.283742 180)
		(property "Reference" "R88"
			(at 0 0 180)
			(layer "F.SilkS")
			(hide yes)
			(effects
				(font
					(size 1.27 1.27)
				)
			)
		)
		(property "Value" ""
			(at 0 0 180)
			(layer "F.Fab")
			(effects
				(font
					(size 1.27 1.27)
				)
			)
		)
		(duplicate_pad_numbers_are_jumpers no)
		(fp_line
			(start 0.7874 0.4064)
			(end -0.7874 0.4064)
			(stroke
				(width 0.1524)
				(type default)
			)
			(layer "F.SilkS")
		)
		(fp_line
			(start 0.7874 -0.4064)
			(end 0.7874 0.4064)
			(stroke
				(width 0.1524)
				(type default)
			)
			(layer "F.SilkS")
		)
		(fp_line
			(start -0.7874 0.4064)
			(end -0.7874 -0.4064)
			(stroke
				(width 0.1524)
				(type default)
			)
			(layer "F.SilkS")
		)
		(fp_line
			(start -0.7874 -0.4064)
			(end 0.7874 -0.4064)
			(stroke
				(width 0.1524)
				(type default)
			)
			(layer "F.SilkS")
		)
		(fp_line
			(start 0.67945 0.3048)
			(end 0.120396 0.3048)
			(stroke
				(width 0.1)
				(type default)
			)
			(layer "F.Fab")
		)
		(fp_line
			(start 0.67945 -0.3048)
			(end 0.67945 0.3048)
			(stroke
				(width 0.1)
				(type default)
			)
			(layer "F.Fab")
		)
		(fp_line
			(start 0.12065 -0.2794)
			(end 0.12065 -0.3048)
			(stroke
				(width 0.1)
				(type default)
			)
			(layer "F.Fab")
		)
		(fp_line
			(start 0.12065 -0.3048)
			(end 0.67945 -0.3048)
			(stroke
				(width 0.1)
				(type default)
			)
			(layer "F.Fab")
		)
		(fp_line
			(start 0.120396 0.3048)
			(end 0.120396 0.2794)
			(stroke
				(width 0.1)
				(type default)
			)
			(layer "F.Fab")
		)
		(fp_line
			(start 0.120396 0.2794)
			(end -0.12065 0.2794)
			(stroke
				(width 0.1)
				(type default)
			)
			(layer "F.Fab")
		)
		(fp_line
			(start -0.12065 0.3048)
			(end -0.67945 0.3048)
			(stroke
				(width 0.1)
				(type default)
			)
			(layer "F.Fab")
		)
		(fp_line
			(start -0.12065 0.2794)
			(end -0.12065 0.3048)
			(stroke
				(width 0.1)
				(type default)
			)
			(layer "F.Fab")
		)
		(fp_line
			(start -0.12065 -0.2794)
			(end 0.12065 -0.2794)
			(stroke
				(width 0.1)
				(type default)
			)
			(layer "F.Fab")
		)
		(fp_line
			(start -0.12065 -0.305054)
			(end -0.12065 -0.2794)
			(stroke
				(width 0.1)
				(type default)
			)
			(layer "F.Fab")
		)
		(fp_line
			(start -0.67945 0.3048)
			(end -0.67945 -0.305054)
			(stroke
				(width 0.1)
				(type default)
			)
			(layer "F.Fab")
		)
		(fp_line
			(start -0.67945 -0.305054)
			(end -0.12065 -0.305054)
			(stroke
				(width 0.1)
				(type default)
			)
			(layer "F.Fab")
		)
		(pad "1" smd circle
			(at -0.40005 0 180)
			(size 0 0)
			(layers "F.Cu" "F.Mask" "F.Paste")
			(net "RST_SMB_NIC1_MUX_ISO_R_N")
		)
		(pad "2" smd circle
			(at 0.40005 0 180)
			(size 0 0)
			(layers "F.Cu" "F.Mask" "F.Paste")
			(net "RST_SMB_NIC1_MUX_ISO_N")
		)
	)
)
